(kicad_pcb
	(version 20260206)
	(generator "pcbnew")
	(generator_version "10.0")
	(general
		(thickness 1.6)
		(legacy_teardrops no)
	)
	(paper "A4")
	(title_block
		(title "Wiwynn_Tioga_Pass_MB.brd")
		(comment 1 "Tioga Pass / footprints 1171-1177 of 4770")
	)
	(layers
		(0 "F.Cu" signal "TOP")
		(4 "In1.Cu" signal "L2GND")
		(6 "In2.Cu" signal "L3")
		(8 "In3.Cu" signal "L4GND")
		(10 "In4.Cu" signal "L5")
		(12 "In5.Cu" signal "L6GND")
		(14 "In6.Cu" signal "L7VCC")
		(16 "In7.Cu" signal "L8VCC")
		(18 "In8.Cu" signal "L9GND")
		(20 "In9.Cu" signal "L10")
		(22 "In10.Cu" signal "L11GND")
		(24 "In11.Cu" signal "L12")
		(26 "In12.Cu" signal "L13GND")
		(2 "B.Cu" signal "BOTTOM")
		(9 "F.Adhes" user "F.Adhesive")
		(11 "B.Adhes" user "B.Adhesive")
		(13 "F.Paste" user "Package Geometry/Pastemask Top")
		(15 "B.Paste" user "Package Geometry/Pastemask Bottom")
		(5 "F.SilkS" user "Ref Des/Silkscreen Top")
		(7 "B.SilkS" user "Ref Des/Silkscreen Bottom")
		(1 "F.Mask" user "Board Geometry/Soldermask Top")
		(3 "B.Mask" user "Board Geometry/Soldermask Bottom")
		(17 "Dwgs.User" user "User.Drawings")
		(19 "Cmts.User" user "User.Comments")
		(21 "Eco1.User" user "User.Eco1")
		(23 "Eco2.User" user "User.Eco2")
		(25 "Edge.Cuts" user "Board Geometry/Outline")
		(27 "Margin" user)
		(31 "F.CrtYd" user "Package Geometry/Place Bound Top")
		(29 "B.CrtYd" user "Package Geometry/Place Bound Bottom")
		(35 "F.Fab" user "Ref Des/Assembly Top")
		(33 "B.Fab" user "Ref Des/Assembly Bottom")
	)
	(footprint ""
		(layer "F.Cu")
		(at 182.118 -65.024)
		(property "Reference" "R4D65"
			(at 0 0 0)
			(layer "F.SilkS")
			(hide yes)
			(effects
				(font
					(size 1.27 1.27)
				)
			)
		)
		(property "Value" ""
			(at 0 0 0)
			(layer "F.Fab")
			(effects
				(font
					(size 1.27 1.27)
				)
			)
		)
		(duplicate_pad_numbers_are_jumpers no)
		(fp_poly
			(pts
				(xy -0.2794 -0.1016) (xy 0.2794 -0.1016) (xy 0.2794 0.9906) (xy -0.2794 0.9906)
			)
			(stroke
				(width 0)
				(type default)
			)
			(fill no)
			(layer "F.CrtYd")
		)
		(fp_line
			(start -0.2794 -0.1016)
			(end -0.2794 0.9906)
			(stroke
				(width 0.1)
				(type default)
			)
			(layer "F.Fab")
		)
		(fp_line
			(start -0.2794 0.9906)
			(end 0.2794 0.9906)
			(stroke
				(width 0.1)
				(type default)
			)
			(layer "F.Fab")
		)
		(fp_line
			(start 0.2794 -0.1016)
			(end -0.2794 -0.1016)
			(stroke
				(width 0.1)
				(type default)
			)
			(layer "F.Fab")
		)
		(fp_line
			(start 0.2794 0.9906)
			(end 0.2794 -0.1016)
			(stroke
				(width 0.1)
				(type default)
			)
			(layer "F.Fab")
		)
		(pad "1" smd rect
			(at 0 0)
			(size 0.508 0.508)
			(layers "F.Cu" "F.Mask" "F.Paste")
			(net "PWRGD_PVSA_CPU0_R")
		)
		(pad "2" smd rect
			(at 0 0.889)
			(size 0.508 0.508)
			(layers "F.Cu" "F.Mask" "F.Paste")
			(net "PWRGD_PVSA_CPU0")
		)
		(zone
			(layer "F.Cu")
			(hatch none 0.5)
			(connect_pads
				(clearance 0)
			)
			(min_thickness 0.25)
			(keepout
				(tracks allowed)
				(vias not_allowed)
				(pads allowed)
				(copperpour not_allowed)
				(footprints allowed)
			)
			(placement
				(enabled no)
				(sheetname "")
			)
			(fill
				(thermal_gap 0.5)
				(thermal_bridge_width 0.5)
				(island_removal_mode 0)
			)
			(polygon
				(pts
					(xy 181.864 -64.77) (xy 182.372 -64.77) (xy 182.372 -64.389) (xy 181.864 -64.389)
				)
			)
		)
		(zone
			(layer "F.Cu")
			(hatch none 0.5)
			(connect_pads
				(clearance 0)
			)
			(min_thickness 0.25)
			(keepout
				(tracks not_allowed)
				(vias allowed)
				(pads allowed)
				(copperpour not_allowed)
				(footprints allowed)
			)
			(placement
				(enabled no)
				(sheetname "")
			)
			(fill
				(thermal_gap 0.5)
				(thermal_bridge_width 0.5)
				(island_removal_mode 0)
			)
			(polygon
				(pts
					(xy 181.864 -64.389) (xy 182.372 -64.389) (xy 182.372 -64.77) (xy 181.864 -64.77)
				)
			)
		)
	)
	(footprint ""
		(layer "F.Cu")
		(at 3.384042 -13.599414 -90)
		(property "Reference" "C1G28"
			(at 0 0 270)
			(layer "F.SilkS")
			(hide yes)
			(effects
				(font
					(size 1.27 1.27)
				)
			)
		)
		(property "Value" ""
			(at 0 0 270)
			(layer "F.Fab")
			(effects
				(font
					(size 1.27 1.27)
				)
			)
		)
		(duplicate_pad_numbers_are_jumpers no)
		(fp_poly
			(pts
				(xy 0.3048 -0.1016) (xy 0.3048 0.9906) (xy -0.3048 0.9906) (xy -0.3048 -0.1016)
			)
			(stroke
				(width 0)
				(type default)
			)
			(fill no)
			(layer "F.CrtYd")
		)
		(fp_line
			(start -0.3048 0.9906)
			(end 0.3048 0.9906)
			(stroke
				(width 0.1)
				(type default)
			)
			(layer "F.Fab")
		)
		(fp_line
			(start 0.3048 0.9906)
			(end 0.3048 -0.1016)
			(stroke
				(width 0.1)
				(type default)
			)
			(layer "F.Fab")
		)
		(fp_line
			(start -0.3048 -0.1016)
			(end -0.3048 0.9906)
			(stroke
				(width 0.1)
				(type default)
			)
			(layer "F.Fab")
		)
		(fp_line
			(start 0.3048 -0.1016)
			(end -0.3048 -0.1016)
			(stroke
				(width 0.1)
				(type default)
			)
			(layer "F.Fab")
		)
		(pad "1" smd rect
			(at 0 0 270)
			(size 0.508 0.508)
			(layers "F.Cu" "F.Mask" "F.Paste")
			(net "VR_PVDDQ_GHJ_PH2_VCIN")
		)
		(pad "2" smd rect
			(at 0 0.889 270)
			(size 0.508 0.508)
			(layers "F.Cu" "F.Mask" "F.Paste")
			(net "GND")
		)
		(zone
			(layer "F.Cu")
			(hatch none 0.5)
			(connect_pads
				(clearance 0)
			)
			(min_thickness 0.25)
			(keepout
				(tracks not_allowed)
				(vias allowed)
				(pads allowed)
				(copperpour not_allowed)
				(footprints allowed)
			)
			(placement
				(enabled no)
				(sheetname "")
			)
			(fill
				(thermal_gap 0.5)
				(thermal_bridge_width 0.5)
				(island_removal_mode 0)
			)
			(polygon
				(pts
					(xy 2.749042 -13.853414) (xy 2.749042 -13.345414) (xy 3.130042 -13.345414) (xy 3.130042 -13.853414)
				)
			)
		)
		(zone
			(layer "F.Cu")
			(hatch none 0.5)
			(connect_pads
				(clearance 0)
			)
			(min_thickness 0.25)
			(keepout
				(tracks allowed)
				(vias not_allowed)
				(pads allowed)
				(copperpour not_allowed)
				(footprints allowed)
			)
			(placement
				(enabled no)
				(sheetname "")
			)
			(fill
				(thermal_gap 0.5)
				(thermal_bridge_width 0.5)
				(island_removal_mode 0)
			)
			(polygon
				(pts
					(xy 3.130042 -13.853414) (xy 3.130042 -13.345414) (xy 2.749042 -13.345414) (xy 2.749042 -13.853414)
				)
			)
		)
	)
	(footprint ""
		(layer "F.Cu")
		(at 406.120092 -10.917936)
		(property "Reference" "C8G6"
			(at 0 0 0)
			(layer "F.SilkS")
			(hide yes)
			(effects
				(font
					(size 1.27 1.27)
				)
			)
		)
		(property "Value" ""
			(at 0 0 0)
			(layer "F.Fab")
			(effects
				(font
					(size 1.27 1.27)
				)
			)
		)
		(duplicate_pad_numbers_are_jumpers no)
		(fp_rect
			(start -0.3048 0.9906)
			(end 0.3048 -0.1016)
			(stroke
				(width 0)
				(type default)
			)
			(fill no)
			(layer "F.CrtYd")
		)
		(fp_line
			(start -0.3048 -0.1016)
			(end -0.3048 0.9906)
			(stroke
				(width 0.1)
				(type default)
			)
			(layer "F.Fab")
		)
		(fp_line
			(start -0.3048 0.9906)
			(end 0.3048 0.9906)
			(stroke
				(width 0.1)
				(type default)
			)
			(layer "F.Fab")
		)
		(fp_line
			(start 0.3048 -0.1016)
			(end -0.3048 -0.1016)
			(stroke
				(width 0.1)
				(type default)
			)
			(layer "F.Fab")
		)
		(fp_line
			(start 0.3048 0.9906)
			(end 0.3048 -0.1016)
			(stroke
				(width 0.1)
				(type default)
			)
			(layer "F.Fab")
		)
		(pad "1" smd rect
			(at 0 0)
			(size 0.508 0.508)
			(layers "F.Cu" "F.Mask" "F.Paste")
			(net "P3E_CPU0_PE2_SS_TXN<2>")
		)
		(pad "2" smd rect
			(at 0 0.889)
			(size 0.508 0.508)
			(layers "F.Cu" "F.Mask" "F.Paste")
			(net "P3E_CPU0_PE2_SS_C_TXN<2>")
		)
		(zone
			(layer "F.Cu")
			(hatch none 0.5)
			(connect_pads
				(clearance 0)
			)
			(min_thickness 0.25)
			(keepout
				(tracks allowed)
				(vias not_allowed)
				(pads allowed)
				(copperpour not_allowed)
				(footprints allowed)
			)
			(placement
				(enabled no)
				(sheetname "")
			)
			(fill
				(thermal_gap 0.5)
				(thermal_bridge_width 0.5)
				(island_removal_mode 0)
			)
			(polygon
				(pts
					(xy 405.866092 -10.282936) (xy 406.374092 -10.282936) (xy 406.374092 -10.663936) (xy 405.866092 -10.663936)
				)
			)
		)
		(zone
			(layer "F.Cu")
			(hatch none 0.5)
			(connect_pads
				(clearance 0)
			)
			(min_thickness 0.25)
			(keepout
				(tracks not_allowed)
				(vias allowed)
				(pads allowed)
				(copperpour not_allowed)
				(footprints allowed)
			)
			(placement
				(enabled no)
				(sheetname "")
			)
			(fill
				(thermal_gap 0.5)
				(thermal_bridge_width 0.5)
				(island_removal_mode 0)
			)
			(polygon
				(pts
					(xy 405.866092 -10.282936) (xy 406.374092 -10.282936) (xy 406.374092 -10.663936) (xy 405.866092 -10.663936)
				)
			)
		)
	)
	(footprint ""
		(layer "F.Cu")
		(at 7.05231 -134.383526 -90)
		(property "Reference" "CT9"
			(at -0.8382 -0.67818 270)
			(unlocked yes)
			(layer "F.SilkS")
			(effects
				(font
					(size 0.4064 0.254)
					(thickness 0.1524)
				)
				(justify left)
			)
		)
		(property "Value" ""
			(at 0 0 270)
			(layer "F.Fab")
			(effects
				(font
					(size 1.27 1.27)
				)
			)
		)
		(duplicate_pad_numbers_are_jumpers no)
		(fp_poly
			(pts
				(xy 0.3048 -0.1016) (xy 0.3048 0.9906) (xy -0.3048 0.9906) (xy -0.3048 -0.1016)
			)
			(stroke
				(width 0)
				(type default)
			)
			(fill no)
			(layer "F.CrtYd")
		)
		(fp_line
			(start -0.3048 0.9906)
			(end 0.3048 0.9906)
			(stroke
				(width 0.1)
				(type default)
			)
			(layer "F.Fab")
		)
		(fp_line
			(start 0.3048 0.9906)
			(end 0.3048 -0.1016)
			(stroke
				(width 0.1)
				(type default)
			)
			(layer "F.Fab")
		)
		(fp_line
			(start -0.3048 -0.1016)
			(end -0.3048 0.9906)
			(stroke
				(width 0.1)
				(type default)
			)
			(layer "F.Fab")
		)
		(fp_line
			(start 0.3048 -0.1016)
			(end -0.3048 -0.1016)
			(stroke
				(width 0.1)
				(type default)
			)
			(layer "F.Fab")
		)
		(pad "1" smd rect
			(at 0 0 270)
			(size 0.508 0.508)
			(layers "F.Cu" "F.Mask" "F.Paste")
			(net "VR_PVDDQ_KLM_PH1_SW")
		)
		(pad "2" smd rect
			(at 0 0.889 270)
			(size 0.508 0.508)
			(layers "F.Cu" "F.Mask" "F.Paste")
			(net "VR_PVDDQ_KLM_PH1_RC")
		)
		(zone
			(layer "F.Cu")
			(hatch none 0.5)
			(connect_pads
				(clearance 0)
			)
			(min_thickness 0.25)
			(keepout
				(tracks not_allowed)
				(vias allowed)
				(pads allowed)
				(copperpour not_allowed)
				(footprints allowed)
			)
			(placement
				(enabled no)
				(sheetname "")
			)
			(fill
				(thermal_gap 0.5)
				(thermal_bridge_width 0.5)
				(island_removal_mode 0)
			)
			(polygon
				(pts
					(xy 6.41731 -134.637526) (xy 6.41731 -134.129526) (xy 6.79831 -134.129526) (xy 6.79831 -134.637526)
				)
			)
		)
		(zone
			(layer "F.Cu")
			(hatch none 0.5)
			(connect_pads
				(clearance 0)
			)
			(min_thickness 0.25)
			(keepout
				(tracks allowed)
				(vias not_allowed)
				(pads allowed)
				(copperpour not_allowed)
				(footprints allowed)
			)
			(placement
				(enabled no)
				(sheetname "")
			)
			(fill
				(thermal_gap 0.5)
				(thermal_bridge_width 0.5)
				(island_removal_mode 0)
			)
			(polygon
				(pts
					(xy 6.79831 -134.637526) (xy 6.79831 -134.129526) (xy 6.41731 -134.129526) (xy 6.41731 -134.637526)
				)
			)
		)
	)
	(footprint ""
		(layer "F.Cu")
		(at 467.36 -134.366 180)
		(property "Reference" "R9B11"
			(at 0 0 180)
			(layer "F.SilkS")
			(hide yes)
			(effects
				(font
					(size 1.27 1.27)
				)
			)
		)
		(property "Value" ""
			(at 0 0 180)
			(layer "F.Fab")
			(effects
				(font
					(size 1.27 1.27)
				)
			)
		)
		(duplicate_pad_numbers_are_jumpers no)
		(fp_poly
			(pts
				(xy -0.2794 -0.1016) (xy 0.2794 -0.1016) (xy 0.2794 0.9906) (xy -0.2794 0.9906)
			)
			(stroke
				(width 0)
				(type default)
			)
			(fill no)
			(layer "F.CrtYd")
		)
		(fp_line
			(start 0.2794 0.9906)
			(end 0.2794 -0.1016)
			(stroke
				(width 0.1)
				(type default)
			)
			(layer "F.Fab")
		)
		(fp_line
			(start 0.2794 -0.1016)
			(end -0.2794 -0.1016)
			(stroke
				(width 0.1)
				(type default)
			)
			(layer "F.Fab")
		)
		(fp_line
			(start -0.2794 0.9906)
			(end 0.2794 0.9906)
			(stroke
				(width 0.1)
				(type default)
			)
			(layer "F.Fab")
		)
		(fp_line
			(start -0.2794 -0.1016)
			(end -0.2794 0.9906)
			(stroke
				(width 0.1)
				(type default)
			)
			(layer "F.Fab")
		)
		(pad "1" smd rect
			(at 0 0 180)
			(size 0.508 0.508)
			(layers "F.Cu" "F.Mask" "F.Paste")
			(net "JTAG_MCP_TCK")
		)
		(pad "2" smd rect
			(at 0 0.889 180)
			(size 0.508 0.508)
			(layers "F.Cu" "F.Mask" "F.Paste")
			(net "JTAG_MCP_TCK_R")
		)
		(zone
			(layer "F.Cu")
			(hatch none 0.5)
			(connect_pads
				(clearance 0)
			)
			(min_thickness 0.25)
			(keepout
				(tracks not_allowed)
				(vias allowed)
				(pads allowed)
				(copperpour not_allowed)
				(footprints allowed)
			)
			(placement
				(enabled no)
				(sheetname "")
			)
			(fill
				(thermal_gap 0.5)
				(thermal_bridge_width 0.5)
				(island_removal_mode 0)
			)
			(polygon
				(pts
					(xy 467.614 -135.001) (xy 467.106 -135.001) (xy 467.106 -134.62) (xy 467.614 -134.62)
				)
			)
		)
		(zone
			(layer "F.Cu")
			(hatch none 0.5)
			(connect_pads
				(clearance 0)
			)
			(min_thickness 0.25)
			(keepout
				(tracks allowed)
				(vias not_allowed)
				(pads allowed)
				(copperpour not_allowed)
				(footprints allowed)
			)
			(placement
				(enabled no)
				(sheetname "")
			)
			(fill
				(thermal_gap 0.5)
				(thermal_bridge_width 0.5)
				(island_removal_mode 0)
			)
			(polygon
				(pts
					(xy 467.614 -134.62) (xy 467.106 -134.62) (xy 467.106 -135.001) (xy 467.614 -135.001)
				)
			)
		)
	)
	(footprint ""
		(layer "F.Cu")
		(at 405.9555 -102.108 -90)
		(property "Reference" "R2N12"
			(at 0 0 270)
			(layer "F.SilkS")
			(hide yes)
			(effects
				(font
					(size 1.27 1.27)
				)
			)
		)
		(property "Value" ""
			(at 0 0 270)
			(layer "F.Fab")
			(effects
				(font
					(size 1.27 1.27)
				)
			)
		)
		(duplicate_pad_numbers_are_jumpers no)
		(fp_poly
			(pts
				(xy -0.2794 -0.1016) (xy 0.2794 -0.1016) (xy 0.2794 0.9906) (xy -0.2794 0.9906)
			)
			(stroke
				(width 0)
				(type default)
			)
			(fill no)
			(layer "F.CrtYd")
		)
		(fp_line
			(start -0.2794 0.9906)
			(end 0.2794 0.9906)
			(stroke
				(width 0.1)
				(type default)
			)
			(layer "F.Fab")
		)
		(fp_line
			(start 0.2794 0.9906)
			(end 0.2794 -0.1016)
			(stroke
				(width 0.1)
				(type default)
			)
			(layer "F.Fab")
		)
		(fp_line
			(start -0.2794 -0.1016)
			(end -0.2794 0.9906)
			(stroke
				(width 0.1)
				(type default)
			)
			(layer "F.Fab")
		)
		(fp_line
			(start 0.2794 -0.1016)
			(end -0.2794 -0.1016)
			(stroke
				(width 0.1)
				(type default)
			)
			(layer "F.Fab")
		)
		(pad "1" smd rect
			(at 0 0 270)
			(size 0.508 0.508)
			(layers "F.Cu" "F.Mask" "F.Paste")
			(net "GND")
		)
		(pad "2" smd rect
			(at 0 0.889 270)
			(size 0.508 0.508)
			(layers "F.Cu" "F.Mask" "F.Paste")
			(net "PWRGD_SYS_PWROK")
		)
		(zone
			(layer "F.Cu")
			(hatch none 0.5)
			(connect_pads
				(clearance 0)
			)
			(min_thickness 0.25)
			(keepout
				(tracks not_allowed)
				(vias allowed)
				(pads allowed)
				(copperpour not_allowed)
				(footprints allowed)
			)
			(placement
				(enabled no)
				(sheetname "")
			)
			(fill
				(thermal_gap 0.5)
				(thermal_bridge_width 0.5)
				(island_removal_mode 0)
			)
			(polygon
				(pts
					(xy 405.3205 -102.362) (xy 405.3205 -101.854) (xy 405.7015 -101.854) (xy 405.7015 -102.362)
				)
			)
		)
		(zone
			(layer "F.Cu")
			(hatch none 0.5)
			(connect_pads
				(clearance 0)
			)
			(min_thickness 0.25)
			(keepout
				(tracks allowed)
				(vias not_allowed)
				(pads allowed)
				(copperpour not_allowed)
				(footprints allowed)
			)
			(placement
				(enabled no)
				(sheetname "")
			)
			(fill
				(thermal_gap 0.5)
				(thermal_bridge_width 0.5)
				(island_removal_mode 0)
			)
			(polygon
				(pts
					(xy 405.7015 -102.362) (xy 405.7015 -101.854) (xy 405.3205 -101.854) (xy 405.3205 -102.362)
				)
			)
		)
	)
	(footprint ""
		(layer "F.Cu")
		(at 276.27072 -83.88604)
		(property "Reference" "R5D2"
			(at 0 0 0)
			(layer "F.SilkS")
			(hide yes)
			(effects
				(font
					(size 1.27 1.27)
				)
			)
		)
		(property "Value" ""
			(at 0 0 0)
			(layer "F.Fab")
			(effects
				(font
					(size 1.27 1.27)
				)
			)
		)
		(duplicate_pad_numbers_are_jumpers no)
		(fp_poly
			(pts
				(xy -0.2794 -0.1016) (xy 0.2794 -0.1016) (xy 0.2794 0.9906) (xy -0.2794 0.9906)
			)
			(stroke
				(width 0)
				(type default)
			)
			(fill no)
			(layer "F.CrtYd")
		)
		(fp_line
			(start -0.2794 -0.1016)
			(end -0.2794 0.9906)
			(stroke
				(width 0.1)
				(type default)
			)
			(layer "F.Fab")
		)
		(fp_line
			(start -0.2794 0.9906)
			(end 0.2794 0.9906)
			(stroke
				(width 0.1)
				(type default)
			)
			(layer "F.Fab")
		)
		(fp_line
			(start 0.2794 -0.1016)
			(end -0.2794 -0.1016)
			(stroke
				(width 0.1)
				(type default)
			)
			(layer "F.Fab")
		)
		(fp_line
			(start 0.2794 0.9906)
			(end 0.2794 -0.1016)
			(stroke
				(width 0.1)
				(type default)
			)
			(layer "F.Fab")
		)
		(pad "1" smd rect
			(at 0 0)
			(size 0.508 0.508)
			(layers "F.Cu" "F.Mask" "F.Paste")
			(net "A_CPU0_DEF_RCOMP1")
		)
		(pad "2" smd rect
			(at 0 0.889)
			(size 0.508 0.508)
			(layers "F.Cu" "F.Mask" "F.Paste")
			(net "GND")
		)
		(zone
			(layer "F.Cu")
			(hatch none 0.5)
			(connect_pads
				(clearance 0)
			)
			(min_thickness 0.25)
			(keepout
				(tracks allowed)
				(vias not_allowed)
				(pads allowed)
				(copperpour not_allowed)
				(footprints allowed)
			)
			(placement
				(enabled no)
				(sheetname "")
			)
			(fill
				(thermal_gap 0.5)
				(thermal_bridge_width 0.5)
				(island_removal_mode 0)
			)
			(polygon
				(pts
					(xy 276.01672 -83.63204) (xy 276.52472 -83.63204) (xy 276.52472 -83.25104) (xy 276.01672 -83.25104)
				)
			)
		)
		(zone
			(layer "F.Cu")
			(hatch none 0.5)
			(connect_pads
				(clearance 0)
			)
			(min_thickness 0.25)
			(keepout
				(tracks not_allowed)
				(vias allowed)
				(pads allowed)
				(copperpour not_allowed)
				(footprints allowed)
			)
			(placement
				(enabled no)
				(sheetname "")
			)
			(fill
				(thermal_gap 0.5)
				(thermal_bridge_width 0.5)
				(island_removal_mode 0)
			)
			(polygon
				(pts
					(xy 276.01672 -83.25104) (xy 276.52472 -83.25104) (xy 276.52472 -83.63204) (xy 276.01672 -83.63204)
				)
			)
		)
	)
)
